#ISCELL
  mstr_misc dns *
  *
#ISCELL
  mstr_symbols cad_note *
  *
#ISCELL
  mstr_symbols intel_corp_bpage *
  *
#ISCELL
  mstr_standard offpage *
  page147_i10
#ISCELL
  mstr_standard offpage *
  page147_i100
#ISCELL
  mstr_standard offpage *
  page147_i102
#ISCELL
  mstr_standard offpage *
  page147_i103
#ISCELL
  mstr_standard offpage *
  page147_i104
#ISCELL
  mstr_standard offpage *
  page147_i105
#CELL
  w_hdl ast2520a1-gp-gp *
  page147_i106
#ISCELL
  mstr_standard offpage *
  page147_i11
#ISCELL
  mstr_standard offpage *
  page147_i12
#ISCELL
  mstr_standard offpage *
  page147_i13
#ISCELL
  mstr_standard offpage *
  page147_i14
#ISCELL
  mstr_standard offpage *
  page147_i15
#ISCELL
  mstr_standard offpage *
  page147_i16
#ISCELL
  mstr_standard offpage *
  page147_i17
#ISCELL
  mstr_standard offpage *
  page147_i18
#ISCELL
  mstr_standard offpage *
  page147_i19
#ISCELL
  mstr_standard offpage *
  page147_i2
#ISCELL
  w_power w_vcc_circle *
  page147_i20
#CELL
  mstr_discrete res *
  page147_i21
#CELL
  mstr_discrete res *
  page147_i22
#CELL
  mstr_discrete res *
  page147_i23
#CELL
  mstr_discrete res *
  page147_i24
#CELL
  mstr_discrete res *
  page147_i25
#ISCELL
  mstr_standard offpage *
  page147_i26
#ISCELL
  mstr_standard offpage *
  page147_i27
#ISCELL
  mstr_standard offpage *
  page147_i28
#ISCELL
  mstr_standard offpage *
  page147_i29
#CELL
  mstr_discrete res *
  page147_i3
#ISCELL
  mstr_standard offpage *
  page147_i30
#ISCELL
  mstr_standard offpage *
  page147_i31
#ISCELL
  mstr_standard offpage *
  page147_i32
#ISCELL
  mstr_standard offpage *
  page147_i33
#ISCELL
  mstr_standard offpage *
  page147_i34
#ISCELL
  mstr_standard offpage *
  page147_i35
#CELL
  mstr_discrete cap *
  page147_i36
#ISCELL
  mstr_symbols gnd *
  page147_i37
#CELL
  mstr_discrete cap *
  page147_i38
#CELL
  mstr_discrete cap *
  page147_i39
#CELL
  mstr_discrete res *
  page147_i4
#CELL
  mstr_discrete res *
  page147_i40
#ISCELL
  mstr_symbols gnd *
  page147_i41
#CELL
  mstr_discrete res *
  page147_i42
#CELL
  mstr_discrete res *
  page147_i43
#ISCELL
  mstr_symbols p3v3_stby *
  page147_i44
#ISCELL
  mstr_standard offpage *
  page147_i45
#ISCELL
  mstr_symbols gnd *
  page147_i46
#ISCELL
  mstr_standard offpage *
  page147_i47
#ISCELL
  mstr_standard offpage *
  page147_i48
#ISCELL
  mstr_standard offpage *
  page147_i49
#ISCELL
  mstr_symbols p3v3_stby *
  page147_i5
#ISCELL
  mstr_standard offpage *
  page147_i50
#ISCELL
  mstr_standard offpage *
  page147_i51
#ISCELL
  mstr_standard offpage *
  page147_i52
#ISCELL
  mstr_standard offpage *
  page147_i53
#ISCELL
  mstr_standard offpage *
  page147_i54
#ISCELL
  mstr_standard offpage *
  page147_i55
#ISCELL
  mstr_standard offpage *
  page147_i56
#ISCELL
  mstr_standard offpage *
  page147_i57
#ISCELL
  mstr_standard offpage *
  page147_i58
#ISCELL
  mstr_standard offpage *
  page147_i59
#ISCELL
  mstr_standard offpage *
  page147_i6
#ISCELL
  mstr_standard offpage *
  page147_i60
#CELL
  mstr_discrete res *
  page147_i61
#CELL
  mstr_discrete res *
  page147_i62
#ISCELL
  mstr_symbols gnd *
  page147_i63
#ISCELL
  mstr_symbols gnd *
  page147_i64
#CELL
  mstr_discrete res *
  page147_i65
#CELL
  mstr_discrete res *
  page147_i66
#ISCELL
  mstr_symbols gnd *
  page147_i67
#ISCELL
  mstr_symbols gnd *
  page147_i68
#ISCELL
  mstr_standard offpage *
  page147_i7
#ISCELL
  mstr_standard offpage *
  page147_i72
#ISCELL
  mstr_standard offpage *
  page147_i73
#CELL
  mstr_discrete res *
  page147_i75
#ISCELL
  mstr_symbols gnd *
  page147_i76
#ISCELL
  mstr_standard offpage *
  page147_i77
#ISCELL
  mstr_standard offpage *
  page147_i79
#CELL
  mstr_discrete res *
  page147_i8
#ISCELL
  mstr_standard offpage *
  page147_i81
#ISCELL
  mstr_standard offpage *
  page147_i84
#ISCELL
  mstr_standard offpage *
  page147_i85
#ISCELL
  mstr_standard offpage *
  page147_i86
#ISCELL
  mstr_standard offpage *
  page147_i87
#ISCELL
  mstr_standard offpage *
  page147_i88
#ISCELL
  mstr_standard offpage *
  page147_i89
#ISCELL
  mstr_standard offpage *
  page147_i9
#ISCELL
  mstr_standard offpage *
  page147_i91
#ISCELL
  mstr_standard offpage *
  page147_i92
#ISCELL
  mstr_standard offpage *
  page147_i93
#ISCELL
  mstr_standard offpage *
  page147_i94
#ISCELL
  mstr_standard offpage *
  page147_i95
#ISCELL
  mstr_standard offpage *
  page147_i96
#ISCELL
  mstr_standard offpage *
  page147_i99
